# S9S_MB_2U (Grand Teton) — schematic netlist excerpt (pin names and nets, part order shuffled) for the footprints in the layout excerpt that follows; sources: Cadence DE-HDL packaged netlist, KiCad conversion of 03242023_DA0F0TMBIJ0_F0T_Motherboard_J_brd_V01_OCP.brd

PR3951  Q_RES  10K 1% CHIP  pkg 0402LF  page 193 : A = P12V_E1S_FLTB_0 ; B = P3V3_AUX
PC2224  Q_CAP  220PF 50V 10% EMPTY  pkg 0402  page 303 : A = HSC_ON ; B = AGND_HSC
C919  Q_CAP_DIFFBUS  DIFF BUS_0.22UF 6.3V 20% X6S  pkg C0201  page 173 : \1\ = P5E_CPU0_PE0_TX_C_DP<7> ; \2\ = P5E_CPU0_PE0_TX_DP<7>

(kicad_pcb
	(version 20260206)
	(generator "pcbnew")
	(generator_version "10.0")
	(general
		(thickness 1.6)
		(legacy_teardrops no)
	)
	(paper "A4")
	(title_block
		(title "03242023_DA0F0TMBIJ0_F0T_Motherboard_J_brd_V01_OCP.brd")
		(comment 1 "Grand Teton / footprints 3785-3787 of 6105")
	)
	(layers
		(0 "F.Cu" signal "TOP")
		(4 "In1.Cu" signal "GND")
		(6 "In2.Cu" signal "IN1")
		(8 "In3.Cu" signal "GND1")
		(10 "In4.Cu" signal "IN2")
		(12 "In5.Cu" signal "GND2")
		(14 "In6.Cu" signal "IN3")
		(16 "In7.Cu" signal "GND3")
		(18 "In8.Cu" signal "VCC")
		(20 "In9.Cu" signal "VCC1")
		(22 "In10.Cu" signal "GND4")
		(24 "In11.Cu" signal "IN4")
		(26 "In12.Cu" signal "GND5")
		(28 "In13.Cu" signal "IN5")
		(30 "In14.Cu" signal "GND6")
		(32 "In15.Cu" signal "IN6")
		(34 "In16.Cu" signal "GND7")
		(2 "B.Cu" signal "BOTTOM")
		(9 "F.Adhes" user "F.Adhesive")
		(11 "B.Adhes" user "B.Adhesive")
		(13 "F.Paste" user "Package Geometry/Pastemask Top")
		(15 "B.Paste" user "Package Geometry/Pastemask Bottom")
		(5 "F.SilkS" user "Ref Des/Silkscreen Top")
		(7 "B.SilkS" user "Ref Des/Silkscreen Bottom")
		(1 "F.Mask" user "Board Geometry/Soldermask Top")
		(3 "B.Mask" user "Board Geometry/Soldermask Bottom")
		(17 "Dwgs.User" user "User.Drawings")
		(19 "Cmts.User" user "User.Comments")
		(21 "Eco1.User" user "User.Eco1")
		(23 "Eco2.User" user "User.Eco2")
		(25 "Edge.Cuts" user "Board Geometry/Outline")
		(27 "Margin" user)
		(31 "F.CrtYd" user "Package Geometry/Place Bound Top")
		(29 "B.CrtYd" user "Package Geometry/Place Bound Bottom")
		(35 "F.Fab" user "Ref Des/Assembly Top")
		(33 "B.Fab" user "Ref Des/Assembly Bottom")
	)
	(footprint ""
		(layer "F.Cu")
		(at 255.37033 -54.844442 90)
		(property "Reference" "PR3951"
			(at 0 0 90)
			(layer "F.SilkS")
			(hide yes)
			(effects
				(font
					(size 1.27 1.27)
				)
			)
		)
		(property "Value" ""
			(at 0 0 90)
			(layer "F.Fab")
			(effects
				(font
					(size 1.27 1.27)
				)
			)
		)
		(duplicate_pad_numbers_are_jumpers no)
		(fp_line
			(start 0.7874 -0.4064)
			(end 0.7874 0.4064)
			(stroke
				(width 0.1524)
				(type default)
			)
			(layer "F.SilkS")
		)
		(fp_line
			(start -0.7874 -0.4064)
			(end 0.7874 -0.4064)
			(stroke
				(width 0.1524)
				(type default)
			)
			(layer "F.SilkS")
		)
		(fp_line
			(start 0.7874 0.4064)
			(end -0.7874 0.4064)
			(stroke
				(width 0.1524)
				(type default)
			)
			(layer "F.SilkS")
		)
		(fp_line
			(start -0.7874 0.4064)
			(end -0.7874 -0.4064)
			(stroke
				(width 0.1524)
				(type default)
			)
			(layer "F.SilkS")
		)
		(fp_line
			(start -0.12065 -0.305054)
			(end -0.12065 -0.2794)
			(stroke
				(width 0.1)
				(type default)
			)
			(layer "F.Fab")
		)
		(fp_line
			(start -0.67945 -0.305054)
			(end -0.12065 -0.305054)
			(stroke
				(width 0.1)
				(type default)
			)
			(layer "F.Fab")
		)
		(fp_line
			(start 0.67945 -0.3048)
			(end 0.67945 0.3048)
			(stroke
				(width 0.1)
				(type default)
			)
			(layer "F.Fab")
		)
		(fp_line
			(start 0.12065 -0.3048)
			(end 0.67945 -0.3048)
			(stroke
				(width 0.1)
				(type default)
			)
			(layer "F.Fab")
		)
		(fp_line
			(start 0.12065 -0.2794)
			(end 0.12065 -0.3048)
			(stroke
				(width 0.1)
				(type default)
			)
			(layer "F.Fab")
		)
		(fp_line
			(start -0.12065 -0.2794)
			(end 0.12065 -0.2794)
			(stroke
				(width 0.1)
				(type default)
			)
			(layer "F.Fab")
		)
		(fp_line
			(start 0.120396 0.2794)
			(end -0.12065 0.2794)
			(stroke
				(width 0.1)
				(type default)
			)
			(layer "F.Fab")
		)
		(fp_line
			(start -0.12065 0.2794)
			(end -0.12065 0.3048)
			(stroke
				(width 0.1)
				(type default)
			)
			(layer "F.Fab")
		)
		(fp_line
			(start 0.67945 0.3048)
			(end 0.120396 0.3048)
			(stroke
				(width 0.1)
				(type default)
			)
			(layer "F.Fab")
		)
		(fp_line
			(start 0.120396 0.3048)
			(end 0.120396 0.2794)
			(stroke
				(width 0.1)
				(type default)
			)
			(layer "F.Fab")
		)
		(fp_line
			(start -0.12065 0.3048)
			(end -0.67945 0.3048)
			(stroke
				(width 0.1)
				(type default)
			)
			(layer "F.Fab")
		)
		(fp_line
			(start -0.67945 0.3048)
			(end -0.67945 -0.305054)
			(stroke
				(width 0.1)
				(type default)
			)
			(layer "F.Fab")
		)
		(pad "1" smd circle
			(at -0.40005 0 90)
			(size 0 0)
			(layers "F.Cu" "F.Mask" "F.Paste")
			(net "P12V_E1S_FLTB_0")
		)
		(pad "2" smd circle
			(at 0.40005 0 90)
			(size 0 0)
			(layers "F.Cu" "F.Mask" "F.Paste")
			(net "P3V3_AUX")
		)
	)
	(footprint ""
		(layer "F.Cu")
		(at 226.733608 -404.823422)
		(property "Reference" "PC2224"
			(at 0 0 0)
			(layer "F.SilkS")
			(hide yes)
			(effects
				(font
					(size 1.27 1.27)
				)
			)
		)
		(property "Value" ""
			(at 0 0 0)
			(layer "F.Fab")
			(effects
				(font
					(size 1.27 1.27)
				)
			)
		)
		(duplicate_pad_numbers_are_jumpers no)
		(fp_line
			(start -0.7874 -0.4064)
			(end 0.7874 -0.4064)
			(stroke
				(width 0.1524)
				(type default)
			)
			(layer "F.SilkS")
		)
		(fp_line
			(start -0.7874 0.4064)
			(end -0.7874 -0.4064)
			(stroke
				(width 0.1524)
				(type default)
			)
			(layer "F.SilkS")
		)
		(fp_line
			(start 0.7874 -0.4064)
			(end 0.7874 0.4064)
			(stroke
				(width 0.1524)
				(type default)
			)
			(layer "F.SilkS")
		)
		(fp_line
			(start 0.7874 0.4064)
			(end -0.7874 0.4064)
			(stroke
				(width 0.1524)
				(type default)
			)
			(layer "F.SilkS")
		)
		(fp_line
			(start -0.67945 -0.305054)
			(end -0.12065 -0.305054)
			(stroke
				(width 0.1)
				(type default)
			)
			(layer "F.Fab")
		)
		(fp_line
			(start -0.67945 0.3048)
			(end -0.67945 -0.305054)
			(stroke
				(width 0.1)
				(type default)
			)
			(layer "F.Fab")
		)
		(fp_line
			(start -0.12065 -0.305054)
			(end -0.12065 -0.2794)
			(stroke
				(width 0.1)
				(type default)
			)
			(layer "F.Fab")
		)
		(fp_line
			(start -0.12065 -0.2794)
			(end 0.12065 -0.2794)
			(stroke
				(width 0.1)
				(type default)
			)
			(layer "F.Fab")
		)
		(fp_line
			(start -0.12065 0.2794)
			(end -0.12065 0.3048)
			(stroke
				(width 0.1)
				(type default)
			)
			(layer "F.Fab")
		)
		(fp_line
			(start -0.12065 0.3048)
			(end -0.67945 0.3048)
			(stroke
				(width 0.1)
				(type default)
			)
			(layer "F.Fab")
		)
		(fp_line
			(start 0.120396 0.2794)
			(end -0.12065 0.2794)
			(stroke
				(width 0.1)
				(type default)
			)
			(layer "F.Fab")
		)
		(fp_line
			(start 0.120396 0.3048)
			(end 0.120396 0.2794)
			(stroke
				(width 0.1)
				(type default)
			)
			(layer "F.Fab")
		)
		(fp_line
			(start 0.12065 -0.3048)
			(end 0.67945 -0.3048)
			(stroke
				(width 0.1)
				(type default)
			)
			(layer "F.Fab")
		)
		(fp_line
			(start 0.12065 -0.2794)
			(end 0.12065 -0.3048)
			(stroke
				(width 0.1)
				(type default)
			)
			(layer "F.Fab")
		)
		(fp_line
			(start 0.67945 -0.3048)
			(end 0.67945 0.3048)
			(stroke
				(width 0.1)
				(type default)
			)
			(layer "F.Fab")
		)
		(fp_line
			(start 0.67945 0.3048)
			(end 0.120396 0.3048)
			(stroke
				(width 0.1)
				(type default)
			)
			(layer "F.Fab")
		)
		(pad "1" smd circle
			(at -0.40005 0)
			(size 0 0)
			(layers "F.Cu" "F.Mask" "F.Paste")
			(net "HSC_ON")
		)
		(pad "2" smd circle
			(at 0.40005 0)
			(size 0 0)
			(layers "F.Cu" "F.Mask" "F.Paste")
			(net "AGND_HSC")
		)
	)
	(footprint ""
		(layer "F.Cu")
		(at 330.721208 -408.517344 -90)
		(property "Reference" "C919"
			(at 0 0 270)
			(layer "F.SilkS")
			(hide yes)
			(effects
				(font
					(size 1.27 1.27)
				)
			)
		)
		(property "Value" ""
			(at 0 0 270)
			(layer "F.Fab")
			(effects
				(font
					(size 1.27 1.27)
				)
			)
		)
		(duplicate_pad_numbers_are_jumpers no)
		(fp_line
			(start -0.299974 0.150114)
			(end -0.299974 -0.150114)
			(stroke
				(width 0.1)
				(type default)
			)
			(layer "F.Fab")
		)
		(fp_line
			(start 0.299974 0.150114)
			(end -0.299974 0.150114)
			(stroke
				(width 0.1)
				(type default)
			)
			(layer "F.Fab")
		)
		(fp_line
			(start -0.299974 -0.150114)
			(end 0.299974 -0.150114)
			(stroke
				(width 0.1)
				(type default)
			)
			(layer "F.Fab")
		)
		(fp_line
			(start 0.299974 -0.150114)
			(end 0.299974 0.150114)
			(stroke
				(width 0.1)
				(type default)
			)
			(layer "F.Fab")
		)
		(pad "1" smd rect
			(at -0.2667 0 270)
			(size 0.3048 0.381)
			(layers "F.Cu" "F.Mask" "F.Paste")
			(net "P5E_CPU0_PE0_TX_C_DP<7>")
		)
		(pad "2" smd rect
			(at 0.2667 0 270)
			(size 0.3048 0.381)
			(layers "F.Cu" "F.Mask" "F.Paste")
			(net "P5E_CPU0_PE0_TX_DP<7>")
		)
	)
)
